(kicad_pcb
	(version 20260206)
	(generator "pcbnew")
	(generator_version "10.0")
	(general
		(thickness 1.6)
		(legacy_teardrops no)
	)
	(paper "A4")
	(title_block
		(title "01162023_DA0F0TEBIF0_F0T_Expander_BD_F_brd_V02_OCP.brd")
		(comment 1 "Grand Teton / footprint 6364 of 9728 (J7), pads 78-142 of 142")
	)
	(layers
		(0 "F.Cu" signal "TOP")
		(4 "In1.Cu" signal "GND")
		(6 "In2.Cu" signal "VCC")
		(8 "In3.Cu" signal "VCC1")
		(10 "In4.Cu" signal "GND1")
		(12 "In5.Cu" signal "IN1")
		(14 "In6.Cu" signal "GND2")
		(16 "In7.Cu" signal "IN2")
		(18 "In8.Cu" signal "GND3")
		(20 "In9.Cu" signal "IN3")
		(22 "In10.Cu" signal "GND4")
		(24 "In11.Cu" signal "IN4")
		(26 "In12.Cu" signal "GND5")
		(28 "In13.Cu" signal "IN5")
		(30 "In14.Cu" signal "GND6")
		(32 "In15.Cu" signal "IN6")
		(34 "In16.Cu" signal "GND7")
		(2 "B.Cu" signal "BOTTOM")
		(9 "F.Adhes" user "F.Adhesive")
		(11 "B.Adhes" user "B.Adhesive")
		(13 "F.Paste" user "Package Geometry/Pastemask Top")
		(15 "B.Paste" user "Package Geometry/Pastemask Bottom")
		(5 "F.SilkS" user "Ref Des/Silkscreen Top")
		(7 "B.SilkS" user "Ref Des/Silkscreen Bottom")
		(1 "F.Mask" user "Board Geometry/Soldermask Top")
		(3 "B.Mask" user "Board Geometry/Soldermask Bottom")
		(17 "Dwgs.User" user "User.Drawings")
		(19 "Cmts.User" user "User.Comments")
		(21 "Eco1.User" user "User.Eco1")
		(23 "Eco2.User" user "User.Eco2")
		(25 "Edge.Cuts" user "Board Geometry/Outline")
		(27 "Margin" user)
		(31 "F.CrtYd" user "Package Geometry/Place Bound Top")
		(29 "B.CrtYd" user "Package Geometry/Place Bound Bottom")
		(35 "F.Fab" user "Ref Des/Assembly Top")
		(33 "B.Fab" user "Ref Des/Assembly Bottom")
	)
	(footprint ""
		(layer "F.Cu")
		(at 287.4899 -412.090108)
		(property "Reference" "J7"
			(at 26.271728 5.314696 90)
			(unlocked yes)
			(layer "F.SilkS")
			(effects
				(font
					(size 2.032 1.524)
					(thickness 0.1524)
				)
				(justify left)
			)
		)
		(property "Value" ""
			(at 0 0 0)
			(layer "F.Fab")
			(effects
				(font
					(size 1.27 1.27)
				)
			)
		)
		(duplicate_pad_numbers_are_jumpers no)
		(pad "N2_3" thru_hole circle
			(at 4.400042 27.29992 180)
			(size 0.906272 0.906272)
			(drill 0.499872)
			(layers "*.Cu" "*.Mask")
			(remove_unused_layers no)
			(net "GND")
			(clearance 0.0508)
			(thermal_gap 0.0508)
		)
		(pad "N2_5" thru_hole circle
			(at 8.800084 27.29992 180)
			(size 0.906272 0.906272)
			(drill 0.499872)
			(layers "*.Cu" "*.Mask")
			(remove_unused_layers no)
			(net "GND")
			(clearance 0.0508)
			(thermal_gap 0.0508)
		)
		(pad "N2_7" thru_hole circle
			(at 13.199872 27.29992 180)
			(size 0.906272 0.906272)
			(drill 0.499872)
			(layers "*.Cu" "*.Mask")
			(remove_unused_layers no)
			(net "GND")
			(clearance 0.0508)
			(thermal_gap 0.0508)
		)
		(pad "N2_9" thru_hole circle
			(at 17.599914 27.29992 180)
			(size 0.906272 0.906272)
			(drill 0.499872)
			(layers "*.Cu" "*.Mask")
			(remove_unused_layers no)
			(net "GND")
			(clearance 0.0508)
			(thermal_gap 0.0508)
		)
		(pad "N10" thru_hole circle
			(at 19.800062 27.500072 180)
			(size 0.71628 0.71628)
			(drill 0.30988)
			(layers "*.Cu" "*.Mask")
			(remove_unused_layers no)
			(net "Net_8798")
			(clearance 0.0508)
			(thermal_gap 0.0508)
		)
		(pad "O9" thru_hole circle
			(at 17.599914 28.599892 180)
			(size 0.71628 0.71628)
			(drill 0.30988)
			(layers "*.Cu" "*.Mask")
			(remove_unused_layers no)
			(net "Net_8796")
			(clearance 0.0508)
			(thermal_gap 0.0508)
		)
		(pad "O10" thru_hole circle
			(at 19.800062 28.800044 180)
			(size 0.71628 0.71628)
			(drill 0.30988)
			(layers "*.Cu" "*.Mask")
			(remove_unused_layers no)
			(net "Net_8797")
			(clearance 0.0508)
			(thermal_gap 0.0508)
		)
		(pad "P2" thru_hole circle
			(at 2.199894 30.100016 180)
			(size 0.906272 0.906272)
			(drill 0.499872)
			(layers "*.Cu" "*.Mask")
			(remove_unused_layers no)
			(net "GND")
			(clearance 0.0508)
			(thermal_gap 0.0508)
		)
		(pad "P4" thru_hole circle
			(at 6.599936 30.100016 180)
			(size 0.906272 0.906272)
			(drill 0.499872)
			(layers "*.Cu" "*.Mask")
			(remove_unused_layers no)
			(net "GND")
			(clearance 0.0508)
			(thermal_gap 0.0508)
		)
		(pad "P6" thru_hole circle
			(at 10.999978 30.100016 180)
			(size 0.906272 0.906272)
			(drill 0.499872)
			(layers "*.Cu" "*.Mask")
			(remove_unused_layers no)
			(net "GND")
			(clearance 0.0508)
			(thermal_gap 0.0508)
		)
		(pad "P8" thru_hole circle
			(at 15.40002 30.100016 180)
			(size 0.906272 0.906272)
			(drill 0.499872)
			(layers "*.Cu" "*.Mask")
			(remove_unused_layers no)
			(net "GND")
			(clearance 0.0508)
			(thermal_gap 0.0508)
		)
		(pad "P9" thru_hole circle
			(at 17.599914 29.900118 180)
			(size 0.71628 0.71628)
			(drill 0.30988)
			(layers "*.Cu" "*.Mask")
			(remove_unused_layers no)
			(net "Net_8795")
			(clearance 0.0508)
			(thermal_gap 0.0508)
		)
		(pad "P10" thru_hole circle
			(at 19.800062 30.100016 180)
			(size 0.906272 0.906272)
			(drill 0.499872)
			(layers "*.Cu" "*.Mask")
			(remove_unused_layers no)
			(net "GND")
			(clearance 0.0508)
			(thermal_gap 0.0508)
		)
		(pad "Q1" thru_hole circle
			(at 0 31.20009 180)
			(size 0.906272 0.906272)
			(drill 0.499872)
			(layers "*.Cu" "*.Mask")
			(remove_unused_layers no)
			(net "GND")
			(clearance 0.0508)
			(thermal_gap 0.0508)
		)
		(pad "Q3" thru_hole circle
			(at 4.400042 31.20009 180)
			(size 0.906272 0.906272)
			(drill 0.499872)
			(layers "*.Cu" "*.Mask")
			(remove_unused_layers no)
			(net "GND")
			(clearance 0.0508)
			(thermal_gap 0.0508)
		)
		(pad "Q5" thru_hole circle
			(at 8.800084 31.20009 180)
			(size 0.906272 0.906272)
			(drill 0.499872)
			(layers "*.Cu" "*.Mask")
			(remove_unused_layers no)
			(net "GND")
			(clearance 0.0508)
			(thermal_gap 0.0508)
		)
		(pad "Q7" thru_hole circle
			(at 13.199872 31.20009 180)
			(size 0.906272 0.906272)
			(drill 0.499872)
			(layers "*.Cu" "*.Mask")
			(remove_unused_layers no)
			(net "GND")
			(clearance 0.0508)
			(thermal_gap 0.0508)
		)
		(pad "Q9" thru_hole circle
			(at 17.599914 31.20009 180)
			(size 0.906272 0.906272)
			(drill 0.499872)
			(layers "*.Cu" "*.Mask")
			(remove_unused_layers no)
			(net "GND")
			(clearance 0.0508)
			(thermal_gap 0.0508)
		)
		(pad "Q10" thru_hole circle
			(at 19.800062 31.399988 180)
			(size 0.71628 0.71628)
			(drill 0.30988)
			(layers "*.Cu" "*.Mask")
			(remove_unused_layers no)
			(net "Net_8794")
			(clearance 0.0508)
			(thermal_gap 0.0508)
		)
		(pad "R9" thru_hole circle
			(at 17.599914 32.500062 180)
			(size 0.71628 0.71628)
			(drill 0.30988)
			(layers "*.Cu" "*.Mask")
			(remove_unused_layers no)
			(net "Net_8792")
			(clearance 0.0508)
			(thermal_gap 0.0508)
		)
		(pad "R10" thru_hole circle
			(at 19.800062 32.69996 180)
			(size 0.71628 0.71628)
			(drill 0.30988)
			(layers "*.Cu" "*.Mask")
			(remove_unused_layers no)
			(net "Net_8793")
			(clearance 0.0508)
			(thermal_gap 0.0508)
		)
		(pad "S2" thru_hole circle
			(at 2.199894 33.999932 180)
			(size 0.906272 0.906272)
			(drill 0.499872)
			(layers "*.Cu" "*.Mask")
			(remove_unused_layers no)
			(net "GND")
			(clearance 0.0508)
			(thermal_gap 0.0508)
		)
		(pad "S4" thru_hole circle
			(at 6.599936 33.999932 180)
			(size 0.906272 0.906272)
			(drill 0.499872)
			(layers "*.Cu" "*.Mask")
			(remove_unused_layers no)
			(net "GND")
			(clearance 0.0508)
			(thermal_gap 0.0508)
		)
		(pad "S6" thru_hole circle
			(at 10.999978 33.999932 180)
			(size 0.906272 0.906272)
			(drill 0.499872)
			(layers "*.Cu" "*.Mask")
			(remove_unused_layers no)
			(net "GND")
			(clearance 0.0508)
			(thermal_gap 0.0508)
		)
		(pad "S8" thru_hole circle
			(at 15.40002 33.999932 180)
			(size 0.906272 0.906272)
			(drill 0.499872)
			(layers "*.Cu" "*.Mask")
			(remove_unused_layers no)
			(net "GND")
			(clearance 0.0508)
			(thermal_gap 0.0508)
		)
		(pad "S9" thru_hole circle
			(at 17.599914 33.800034 180)
			(size 0.71628 0.71628)
			(drill 0.30988)
			(layers "*.Cu" "*.Mask")
			(remove_unused_layers no)
			(net "Net_8791")
			(clearance 0.0508)
			(thermal_gap 0.0508)
		)
		(pad "S10" thru_hole circle
			(at 19.800062 33.999932 180)
			(size 0.906272 0.906272)
			(drill 0.499872)
			(layers "*.Cu" "*.Mask")
			(remove_unused_layers no)
			(net "GND")
			(clearance 0.0508)
			(thermal_gap 0.0508)
		)
		(pad "T1" thru_hole circle
			(at 0 35.100006 180)
			(size 0.906272 0.906272)
			(drill 0.499872)
			(layers "*.Cu" "*.Mask")
			(remove_unused_layers no)
			(net "GND")
			(clearance 0.0508)
			(thermal_gap 0.0508)
		)
		(pad "T3" thru_hole circle
			(at 4.400042 35.100006 180)
			(size 0.906272 0.906272)
			(drill 0.499872)
			(layers "*.Cu" "*.Mask")
			(remove_unused_layers no)
			(net "GND")
			(clearance 0.0508)
			(thermal_gap 0.0508)
		)
		(pad "T5" thru_hole circle
			(at 8.800084 35.100006 180)
			(size 0.906272 0.906272)
			(drill 0.499872)
			(layers "*.Cu" "*.Mask")
			(remove_unused_layers no)
			(net "GND")
			(clearance 0.0508)
			(thermal_gap 0.0508)
		)
		(pad "T7" thru_hole circle
			(at 13.199872 35.100006 180)
			(size 0.906272 0.906272)
			(drill 0.499872)
			(layers "*.Cu" "*.Mask")
			(remove_unused_layers no)
			(net "GND")
			(clearance 0.0508)
			(thermal_gap 0.0508)
		)
		(pad "T9" thru_hole circle
			(at 17.599914 35.100006 180)
			(size 0.906272 0.906272)
			(drill 0.499872)
			(layers "*.Cu" "*.Mask")
			(remove_unused_layers no)
			(net "GND")
			(clearance 0.0508)
			(thermal_gap 0.0508)
		)
		(pad "T10" thru_hole circle
			(at 19.800062 35.299904 180)
			(size 0.71628 0.71628)
			(drill 0.30988)
			(layers "*.Cu" "*.Mask")
			(remove_unused_layers no)
			(net "Net_8790")
			(clearance 0.0508)
			(thermal_gap 0.0508)
		)
		(pad "U9" thru_hole circle
			(at 17.599914 36.399978 180)
			(size 0.71628 0.71628)
			(drill 0.30988)
			(layers "*.Cu" "*.Mask")
			(remove_unused_layers no)
			(net "Net_8788")
			(clearance 0.0508)
			(thermal_gap 0.0508)
		)
		(pad "U10" thru_hole circle
			(at 19.800062 36.599876 180)
			(size 0.71628 0.71628)
			(drill 0.30988)
			(layers "*.Cu" "*.Mask")
			(remove_unused_layers no)
			(net "Net_8789")
			(clearance 0.0508)
			(thermal_gap 0.0508)
		)
		(pad "V2" thru_hole circle
			(at 2.199894 37.900102 180)
			(size 0.906272 0.906272)
			(drill 0.499872)
			(layers "*.Cu" "*.Mask")
			(remove_unused_layers no)
			(net "GND")
			(clearance 0.0508)
			(thermal_gap 0.0508)
		)
		(pad "V4" thru_hole circle
			(at 6.599936 37.900102 180)
			(size 0.906272 0.906272)
			(drill 0.499872)
			(layers "*.Cu" "*.Mask")
			(remove_unused_layers no)
			(net "GND")
			(clearance 0.0508)
			(thermal_gap 0.0508)
		)
		(pad "V6" thru_hole circle
			(at 10.999978 37.900102 180)
			(size 0.906272 0.906272)
			(drill 0.499872)
			(layers "*.Cu" "*.Mask")
			(remove_unused_layers no)
			(net "GND")
			(clearance 0.0508)
			(thermal_gap 0.0508)
		)
		(pad "V8" thru_hole circle
			(at 15.40002 37.900102 180)
			(size 0.906272 0.906272)
			(drill 0.499872)
			(layers "*.Cu" "*.Mask")
			(remove_unused_layers no)
			(net "GND")
			(clearance 0.0508)
			(thermal_gap 0.0508)
		)
		(pad "V9" thru_hole circle
			(at 17.599914 37.69995 180)
			(size 0.71628 0.71628)
			(drill 0.30988)
			(layers "*.Cu" "*.Mask")
			(remove_unused_layers no)
			(net "Net_8787")
			(clearance 0.0508)
			(thermal_gap 0.0508)
		)
		(pad "V10" thru_hole circle
			(at 19.800062 37.900102 180)
			(size 0.906272 0.906272)
			(drill 0.499872)
			(layers "*.Cu" "*.Mask")
			(remove_unused_layers no)
			(net "GND")
			(clearance 0.0508)
			(thermal_gap 0.0508)
		)
		(pad "W1" thru_hole circle
			(at 0 38.999922 180)
			(size 0.906272 0.906272)
			(drill 0.499872)
			(layers "*.Cu" "*.Mask")
			(remove_unused_layers no)
			(net "GND")
			(clearance 0.0508)
			(thermal_gap 0.0508)
		)
		(pad "W3" thru_hole circle
			(at 4.400042 38.999922 180)
			(size 0.906272 0.906272)
			(drill 0.499872)
			(layers "*.Cu" "*.Mask")
			(remove_unused_layers no)
			(net "GND")
			(clearance 0.0508)
			(thermal_gap 0.0508)
		)
		(pad "W5" thru_hole circle
			(at 8.800084 38.999922 180)
			(size 0.906272 0.906272)
			(drill 0.499872)
			(layers "*.Cu" "*.Mask")
			(remove_unused_layers no)
			(net "GND")
			(clearance 0.0508)
			(thermal_gap 0.0508)
		)
		(pad "W7" thru_hole circle
			(at 13.199872 38.999922 180)
			(size 0.906272 0.906272)
			(drill 0.499872)
			(layers "*.Cu" "*.Mask")
			(remove_unused_layers no)
			(net "GND")
			(clearance 0.0508)
			(thermal_gap 0.0508)
		)
		(pad "W9" thru_hole circle
			(at 17.599914 38.999922 180)
			(size 0.906272 0.906272)
			(drill 0.499872)
			(layers "*.Cu" "*.Mask")
			(remove_unused_layers no)
			(net "GND")
			(clearance 0.0508)
			(thermal_gap 0.0508)
		)
		(pad "W10" thru_hole circle
			(at 19.800062 39.200074 180)
			(size 0.71628 0.71628)
			(drill 0.30988)
			(layers "*.Cu" "*.Mask")
			(remove_unused_layers no)
			(net "Net_8786")
			(clearance 0.0508)
			(thermal_gap 0.0508)
		)
		(pad "X9" thru_hole circle
			(at 17.599914 40.299894 180)
			(size 0.71628 0.71628)
			(drill 0.30988)
			(layers "*.Cu" "*.Mask")
			(remove_unused_layers no)
			(net "Net_8784")
			(clearance 0.0508)
			(thermal_gap 0.0508)
		)
		(pad "X10" thru_hole circle
			(at 19.800062 40.500046 180)
			(size 0.71628 0.71628)
			(drill 0.30988)
			(layers "*.Cu" "*.Mask")
			(remove_unused_layers no)
			(net "Net_8785")
			(clearance 0.0508)
			(thermal_gap 0.0508)
		)
		(pad "Y2" thru_hole circle
			(at 2.199894 41.800018 180)
			(size 0.906272 0.906272)
			(drill 0.499872)
			(layers "*.Cu" "*.Mask")
			(remove_unused_layers no)
			(net "GND")
			(clearance 0.0508)
			(thermal_gap 0.0508)
		)
		(pad "Y4" thru_hole circle
			(at 6.599936 41.800018 180)
			(size 0.906272 0.906272)
			(drill 0.499872)
			(layers "*.Cu" "*.Mask")
			(remove_unused_layers no)
			(net "GND")
			(clearance 0.0508)
			(thermal_gap 0.0508)
		)
		(pad "Y6" thru_hole circle
			(at 10.999978 41.800018 180)
			(size 0.906272 0.906272)
			(drill 0.499872)
			(layers "*.Cu" "*.Mask")
			(remove_unused_layers no)
			(net "GND")
			(clearance 0.0508)
			(thermal_gap 0.0508)
		)
		(pad "Y8" thru_hole circle
			(at 15.40002 41.800018 180)
			(size 0.906272 0.906272)
			(drill 0.499872)
			(layers "*.Cu" "*.Mask")
			(remove_unused_layers no)
			(net "GND")
			(clearance 0.0508)
			(thermal_gap 0.0508)
		)
		(pad "Y9" thru_hole circle
			(at 17.599914 41.60012 180)
			(size 0.71628 0.71628)
			(drill 0.30988)
			(layers "*.Cu" "*.Mask")
			(remove_unused_layers no)
			(net "Net_8783")
			(clearance 0.0508)
			(thermal_gap 0.0508)
		)
		(pad "Y10" thru_hole circle
			(at 19.800062 41.800018 180)
			(size 0.906272 0.906272)
			(drill 0.499872)
			(layers "*.Cu" "*.Mask")
			(remove_unused_layers no)
			(net "GND")
			(clearance 0.0508)
			(thermal_gap 0.0508)
		)
		(pad "Z1" thru_hole circle
			(at 0 42.900092 180)
			(size 0.906272 0.906272)
			(drill 0.499872)
			(layers "*.Cu" "*.Mask")
			(remove_unused_layers no)
			(net "GND")
			(clearance 0.0508)
			(thermal_gap 0.0508)
		)
		(pad "Z2" thru_hole circle
			(at 2.199894 43.09999 180)
			(size 0.71628 0.71628)
			(drill 0.30988)
			(layers "*.Cu" "*.Mask")
			(remove_unused_layers no)
			(net "Net_8819")
			(clearance 0.0508)
			(thermal_gap 0.0508)
		)
		(pad "Z3" thru_hole circle
			(at 4.400042 42.900092 180)
			(size 0.906272 0.906272)
			(drill 0.499872)
			(layers "*.Cu" "*.Mask")
			(remove_unused_layers no)
			(net "GND")
			(clearance 0.0508)
			(thermal_gap 0.0508)
		)
		(pad "Z4" thru_hole circle
			(at 6.599936 43.09999 180)
			(size 0.71628 0.71628)
			(drill 0.30988)
			(layers "*.Cu" "*.Mask")
			(remove_unused_layers no)
			(net "Net_8818")
			(clearance 0.0508)
			(thermal_gap 0.0508)
		)
		(pad "Z5" thru_hole circle
			(at 8.800084 42.900092 180)
			(size 0.906272 0.906272)
			(drill 0.499872)
			(layers "*.Cu" "*.Mask")
			(remove_unused_layers no)
			(net "GND")
			(clearance 0.0508)
			(thermal_gap 0.0508)
		)
		(pad "Z6" thru_hole circle
			(at 10.999978 43.09999 180)
			(size 0.71628 0.71628)
			(drill 0.30988)
			(layers "*.Cu" "*.Mask")
			(remove_unused_layers no)
			(net "Net_8817")
			(clearance 0.0508)
			(thermal_gap 0.0508)
		)
		(pad "Z7" thru_hole circle
			(at 13.199872 42.900092 180)
			(size 0.906272 0.906272)
			(drill 0.499872)
			(layers "*.Cu" "*.Mask")
			(remove_unused_layers no)
			(net "GND")
			(clearance 0.0508)
			(thermal_gap 0.0508)
		)
		(pad "Z8" thru_hole circle
			(at 15.40002 43.09999 180)
			(size 0.71628 0.71628)
			(drill 0.30988)
			(layers "*.Cu" "*.Mask")
			(remove_unused_layers no)
			(net "Net_8816")
			(clearance 0.0508)
			(thermal_gap 0.0508)
		)
		(pad "Z9" thru_hole circle
			(at 17.599914 42.900092 180)
			(size 0.906272 0.906272)
			(drill 0.499872)
			(layers "*.Cu" "*.Mask")
			(remove_unused_layers no)
			(net "GND")
			(clearance 0.0508)
			(thermal_gap 0.0508)
		)
		(pad "Z10" thru_hole circle
			(at 19.800062 43.09999 180)
			(size 0.71628 0.71628)
			(drill 0.30988)
			(layers "*.Cu" "*.Mask")
			(remove_unused_layers no)
			(net "Net_8782")
			(clearance 0.0508)
			(thermal_gap 0.0508)
		)
	)
)
